# S9S_MB_2U (Grand Teton) — schematic netlist excerpt (pin names and nets, part order shuffled) for the footprints in the layout excerpt that follows; sources: Cadence DE-HDL packaged netlist, KiCad conversion of 03242023_DA0F0TMBIJ0_F0T_Motherboard_J_brd_V01_OCP.brd

U205  TPS3700DDCR  EMPTY  pkg SOT23-6XF  page 306
  OUTA  = PWRGD_DSW_PWROK_R4
  GND  = GND
  \ina+\  = A_HSC_INAP
  \inb-\  = NC_U205_INB-
  VDD  = U205_VDD
  OUTB  = NC_U205_OUTB

R3523  Q_RES  54.9K 1% CHIP  pkg 0402LF  page 234 : A = P3V3_AUX ; B = SMB_1_BMC_GPU_BUF_R_SCL

(kicad_pcb
	(version 20260206)
	(generator "pcbnew")
	(generator_version "10.0")
	(general
		(thickness 1.6)
		(legacy_teardrops no)
	)
	(paper "A4")
	(title_block
		(title "03242023_DA0F0TMBIJ0_F0T_Motherboard_J_brd_V01_OCP.brd")
		(comment 1 "Grand Teton / footprints 642-643 of 6105")
	)
	(layers
		(0 "F.Cu" signal "TOP")
		(4 "In1.Cu" signal "GND")
		(6 "In2.Cu" signal "IN1")
		(8 "In3.Cu" signal "GND1")
		(10 "In4.Cu" signal "IN2")
		(12 "In5.Cu" signal "GND2")
		(14 "In6.Cu" signal "IN3")
		(16 "In7.Cu" signal "GND3")
		(18 "In8.Cu" signal "VCC")
		(20 "In9.Cu" signal "VCC1")
		(22 "In10.Cu" signal "GND4")
		(24 "In11.Cu" signal "IN4")
		(26 "In12.Cu" signal "GND5")
		(28 "In13.Cu" signal "IN5")
		(30 "In14.Cu" signal "GND6")
		(32 "In15.Cu" signal "IN6")
		(34 "In16.Cu" signal "GND7")
		(2 "B.Cu" signal "BOTTOM")
		(9 "F.Adhes" user "F.Adhesive")
		(11 "B.Adhes" user "B.Adhesive")
		(13 "F.Paste" user "Package Geometry/Pastemask Top")
		(15 "B.Paste" user "Package Geometry/Pastemask Bottom")
		(5 "F.SilkS" user "Ref Des/Silkscreen Top")
		(7 "B.SilkS" user "Ref Des/Silkscreen Bottom")
		(1 "F.Mask" user "Board Geometry/Soldermask Top")
		(3 "B.Mask" user "Board Geometry/Soldermask Bottom")
		(17 "Dwgs.User" user "User.Drawings")
		(19 "Cmts.User" user "User.Comments")
		(21 "Eco1.User" user "User.Eco1")
		(23 "Eco2.User" user "User.Eco2")
		(25 "Edge.Cuts" user "Board Geometry/Outline")
		(27 "Margin" user)
		(31 "F.CrtYd" user "Package Geometry/Place Bound Top")
		(29 "B.CrtYd" user "Package Geometry/Place Bound Bottom")
		(35 "F.Fab" user "Ref Des/Assembly Top")
		(33 "B.Fab" user "Ref Des/Assembly Bottom")
	)
	(footprint ""
		(layer "F.Cu")
		(at 38.02888 -434.939948)
		(property "Reference" "R3523"
			(at 0 0 0)
			(layer "F.SilkS")
			(hide yes)
			(effects
				(font
					(size 1.27 1.27)
				)
			)
		)
		(property "Value" ""
			(at 0 0 0)
			(layer "F.Fab")
			(effects
				(font
					(size 1.27 1.27)
				)
			)
		)
		(duplicate_pad_numbers_are_jumpers no)
		(fp_line
			(start -0.7874 -0.4064)
			(end 0.7874 -0.4064)
			(stroke
				(width 0.1524)
				(type default)
			)
			(layer "F.SilkS")
		)
		(fp_line
			(start -0.7874 0.4064)
			(end -0.7874 -0.4064)
			(stroke
				(width 0.1524)
				(type default)
			)
			(layer "F.SilkS")
		)
		(fp_line
			(start 0.7874 -0.4064)
			(end 0.7874 0.4064)
			(stroke
				(width 0.1524)
				(type default)
			)
			(layer "F.SilkS")
		)
		(fp_line
			(start 0.7874 0.4064)
			(end -0.7874 0.4064)
			(stroke
				(width 0.1524)
				(type default)
			)
			(layer "F.SilkS")
		)
		(fp_line
			(start -0.67945 -0.305054)
			(end -0.12065 -0.305054)
			(stroke
				(width 0.1)
				(type default)
			)
			(layer "F.Fab")
		)
		(fp_line
			(start -0.67945 0.3048)
			(end -0.67945 -0.305054)
			(stroke
				(width 0.1)
				(type default)
			)
			(layer "F.Fab")
		)
		(fp_line
			(start -0.12065 -0.305054)
			(end -0.12065 -0.2794)
			(stroke
				(width 0.1)
				(type default)
			)
			(layer "F.Fab")
		)
		(fp_line
			(start -0.12065 -0.2794)
			(end 0.12065 -0.2794)
			(stroke
				(width 0.1)
				(type default)
			)
			(layer "F.Fab")
		)
		(fp_line
			(start -0.12065 0.2794)
			(end -0.12065 0.3048)
			(stroke
				(width 0.1)
				(type default)
			)
			(layer "F.Fab")
		)
		(fp_line
			(start -0.12065 0.3048)
			(end -0.67945 0.3048)
			(stroke
				(width 0.1)
				(type default)
			)
			(layer "F.Fab")
		)
		(fp_line
			(start 0.120396 0.2794)
			(end -0.12065 0.2794)
			(stroke
				(width 0.1)
				(type default)
			)
			(layer "F.Fab")
		)
		(fp_line
			(start 0.120396 0.3048)
			(end 0.120396 0.2794)
			(stroke
				(width 0.1)
				(type default)
			)
			(layer "F.Fab")
		)
		(fp_line
			(start 0.12065 -0.3048)
			(end 0.67945 -0.3048)
			(stroke
				(width 0.1)
				(type default)
			)
			(layer "F.Fab")
		)
		(fp_line
			(start 0.12065 -0.2794)
			(end 0.12065 -0.3048)
			(stroke
				(width 0.1)
				(type default)
			)
			(layer "F.Fab")
		)
		(fp_line
			(start 0.67945 -0.3048)
			(end 0.67945 0.3048)
			(stroke
				(width 0.1)
				(type default)
			)
			(layer "F.Fab")
		)
		(fp_line
			(start 0.67945 0.3048)
			(end 0.120396 0.3048)
			(stroke
				(width 0.1)
				(type default)
			)
			(layer "F.Fab")
		)
		(pad "1" smd circle
			(at -0.40005 0)
			(size 0 0)
			(layers "F.Cu" "F.Mask" "F.Paste")
			(net "P3V3_AUX")
		)
		(pad "2" smd circle
			(at 0.40005 0)
			(size 0 0)
			(layers "F.Cu" "F.Mask" "F.Paste")
			(net "SMB_1_BMC_GPU_BUF_R_SCL")
		)
	)
	(footprint ""
		(layer "F.Cu")
		(at 215.33739 -104.33304 180)
		(property "Reference" "U205"
			(at 6.09854 -2.351532 0)
			(unlocked yes)
			(layer "F.SilkS")
			(effects
				(font
					(size 0.7874 0.5842)
					(thickness 0.1524)
				)
				(justify left)
			)
		)
		(property "Value" ""
			(at 0 0 180)
			(layer "F.Fab")
			(effects
				(font
					(size 1.27 1.27)
				)
			)
		)
		(duplicate_pad_numbers_are_jumpers no)
		(fp_line
			(start 2.03581 1.525016)
			(end 2.03581 -1.525016)
			(stroke
				(width 0.1524)
				(type default)
			)
			(layer "F.SilkS")
		)
		(fp_line
			(start 2.03581 -1.525016)
			(end 0.82423 -1.525016)
			(stroke
				(width 0.1524)
				(type default)
			)
			(layer "F.SilkS")
		)
		(fp_line
			(start 0.82423 -1.525016)
			(end 0 -0.649986)
			(stroke
				(width 0.1524)
				(type default)
			)
			(layer "F.SilkS")
		)
		(fp_line
			(start 0 -0.649986)
			(end -0.82423 -1.525016)
			(stroke
				(width 0.1524)
				(type default)
			)
			(layer "F.SilkS")
		)
		(fp_line
			(start -0.82423 -1.525016)
			(end -2.03581 -1.525016)
			(stroke
				(width 0.1524)
				(type default)
			)
			(layer "F.SilkS")
		)
		(fp_line
			(start -2.03581 1.525016)
			(end 2.03581 1.525016)
			(stroke
				(width 0.1524)
				(type default)
			)
			(layer "F.SilkS")
		)
		(fp_line
			(start -2.03581 -1.525016)
			(end -2.03581 1.525016)
			(stroke
				(width 0.1524)
				(type default)
			)
			(layer "F.SilkS")
		)
		(fp_poly
			(pts
				(xy -2.335276 -1.224788) (xy -3.151378 -1.497076) (xy -2.60731 -2.041144)
			)
			(stroke
				(width 0)
				(type default)
			)
			(fill yes)
			(layer "F.SilkS")
		)
		(fp_line
			(start 0.87503 1.525016)
			(end 0.87503 -1.525016)
			(stroke
				(width 0.1)
				(type default)
			)
			(layer "F.Fab")
		)
		(fp_line
			(start 0.87503 -1.525016)
			(end -0.87503 -1.525016)
			(stroke
				(width 0.1)
				(type default)
			)
			(layer "F.Fab")
		)
		(fp_line
			(start -0.87503 1.525016)
			(end 0.87503 1.525016)
			(stroke
				(width 0.1)
				(type default)
			)
			(layer "F.Fab")
		)
		(fp_line
			(start -0.87503 -1.525016)
			(end -0.87503 1.525016)
			(stroke
				(width 0.1)
				(type default)
			)
			(layer "F.Fab")
		)
		(fp_poly
			(pts
				(xy -2.12979 -0.943356) (xy -2.89941 -0.5588) (xy -2.89941 -1.328166)
			)
			(stroke
				(width 0)
				(type default)
			)
			(fill yes)
			(layer "F.Fab")
		)
		(pad "1" smd rect
			(at -1.35001 -0.94996 90)
			(size 0.6096 1.1176)
			(layers "F.Cu" "F.Mask" "F.Paste")
			(net "PWRGD_DSW_PWROK_R4")
		)
		(pad "2" smd rect
			(at -1.35001 0 90)
			(size 0.6096 1.1176)
			(layers "F.Cu" "F.Mask" "F.Paste")
			(net "GND")
		)
		(pad "3" smd rect
			(at -1.35001 0.94996 90)
			(size 0.6096 1.1176)
			(layers "F.Cu" "F.Mask" "F.Paste")
			(net "A_HSC_INAP")
		)
		(pad "4" smd rect
			(at 1.35001 0.94996 90)
			(size 0.6096 1.1176)
			(layers "F.Cu" "F.Mask" "F.Paste")
			(net "NC_U205_INB-")
		)
		(pad "5" smd rect
			(at 1.35001 0 90)
			(size 0.6096 1.1176)
			(layers "F.Cu" "F.Mask" "F.Paste")
			(net "U205_VDD")
		)
		(pad "6" smd rect
			(at 1.35001 -0.94996 90)
			(size 0.6096 1.1176)
			(layers "F.Cu" "F.Mask" "F.Paste")
			(net "NC_U205_OUTB")
		)
	)
)
